FILE_TYPE = MACRO_DRAWING;
SET COLOR_WIRE YELLOW;
SET COLOR_PROP MONO;
SET COLOR_DOT WHITE;
SET COLOR_ARC YELLOW;
SET COLOR_BODY GREEN;
SET COLOR_NOTE MONO;
SET PROP_DISPLAY VALUE;
SET PAGE_NUMBER P177;
FORCEADD OFFPAGE..1
(-8650 6225);
FORCEPROP 2 LAST $XR0 120 
J 0
(-8932 6225);
DISPLAY 0.638298 (-8932 6225);
PAINT MONO (-8932 6225);
FORCEPROP 2 LAST CDS_LIB mstr_standard
J 0
(-8650 6225);
DISPLAY 1.361702 (-8650 6225);
PAINT ORANGE (-8650 6225);
DISPLAY INVISIBLE (-8650 6225);
FORCEPROP 2 LAST ROOM MIO_CHASSIS
J 0
(-8850 6275);
DISPLAY 1.404255 (-8850 6275);
PAINT ORANGE (-8850 6275);
DISPLAY INVISIBLE (-8850 6275);
FORCEPROP 2 LAST PATH I1
J 0
(-8900 6275);
DISPLAY 1.021277 (-8900 6275);
PAINT ORANGE (-8900 6275);
DISPLAY INVISIBLE (-8900 6275);
FORCEPROP 1 LAST OFFPAGE TRUE
J 0
(-8325 6100);
PAINT GREEN (-8325 6100);
DISPLAY INVISIBLE (-8325 6100);
FORCEPROP 1 LAST COMMENT_BODY TRUE
J 0
(-8525 6125);
DISPLAY 1.170213 (-8525 6125);
PAINT GREEN (-8525 6125);
DISPLAY INVISIBLE (-8525 6125);
FORCEADD P3V3..1
(-6975 6775);
FORCEPROP 3 LASTPIN (-6975 6725) SIG_NAME P3V3\g
J 0
(-6965 6735);
DISPLAY 0.659574 (-6965 6735);
PAINT MONO (-6965 6735);
DISPLAY INVISIBLE (-6965 6735);
FORCEPROP 1 LAST VOLTAGE +3.3
J 0
(-6975 6775);
PAINT SKYBLUE (-6975 6775);
DISPLAY INVISIBLE (-6975 6775);
FORCEPROP 1 LAST SIZE 1B
J 0
(-6930 6797);
DISPLAY 0.553191 (-6930 6797);
PAINT GREEN (-6930 6797);
DISPLAY INVISIBLE (-6930 6797);
FORCEPROP 2 LAST CDS_LIB mstr_symbols
J 0
(-6975 6775);
DISPLAY 1.361702 (-6975 6775);
PAINT ORANGE (-6975 6775);
DISPLAY INVISIBLE (-6975 6775);
FORCEPROP 1 LAST PATH I10
J 0
(-6930 6777);
DISPLAY 0.340426 (-6930 6777);
PAINT GREEN (-6930 6777);
DISPLAY INVISIBLE (-6930 6777);
FORCEPROP 2 LAST ROOM SB
J 0
(-7425 6875);
DISPLAY 1.404255 (-7425 6875);
PAINT ORANGE (-7425 6875);
DISPLAY INVISIBLE (-7425 6875);
FORCEPROP 1 LAST BODY_TYPE PLUMBING
J 0
(-7020 6732);
DISPLAY 0.468085 (-7020 6732);
PAINT GREEN (-7020 6732);
DISPLAY INVISIBLE (-7020 6732);
FORCEPROP 1 LAST HDL_POWER P3V3
J 0
(-7300 6650);
DISPLAY 1.170213 (-7300 6650);
PAINT GREEN (-7300 6650);
DISPLAY INVISIBLE (-7300 6650);
FORCEADD CAP_A..1
(-5625 5425);
FORCEPROP 1 LAST LOCATION C1M3
J 0
(-5575 5525);
DISPLAY 0.617021 (-5575 5525);
PAINT AQUA (-5575 5525);
FORCEPROP 1 LAST PART_NUMBER D97712-004
J 0
(-5575 5275);
DISPLAY 0.617021 (-5575 5275);
PAINT BLUE (-5575 5275);
FORCEPROP 1 LAST VALUE 1.0UF
J 0
(-5575 5475);
DISPLAY 0.617021 (-5575 5475);
PAINT SKYBLUE (-5575 5475);
FORCEPROP 1 LAST TOLERANCE 10%
J 0
(-5575 5375);
DISPLAY 0.617021 (-5575 5375);
PAINT SKYBLUE (-5575 5375);
FORCEPROP 1 LAST PACK_TYPE 0402V
J 0
(-5575 5225);
DISPLAY 0.617021 (-5575 5225);
PAINT SKYBLUE (-5575 5225);
FORCEPROP 1 LAST VOLTAGE 6.3V
J 0
(-5575 5425);
DISPLAY 0.617021 (-5575 5425);
PAINT SKYBLUE (-5575 5425);
FORCEPROP 1 LAST MATERIAL X6S
J 0
(-5575 5325);
DISPLAY 0.617021 (-5575 5325);
PAINT SKYBLUE (-5575 5325);
FORCEPROP 1 LASTPIN (-5625 5525) $PN 1
J 0
(-5615 5505);
DISPLAY 0.617021 (-5615 5505);
PAINT MONO (-5615 5505);
FORCEPROP 1 LASTPIN (-5625 5325) $PN 2
J 0
(-5615 5305);
DISPLAY 0.617021 (-5615 5305);
PAINT MONO (-5615 5305);
FORCEPROP 2 LAST CDS_LOCATION C1M3
J 0
(-5575 5525);
DISPLAY 0.617021 (-5575 5525);
PAINT AQUA (-5575 5525);
DISPLAY INVISIBLE (-5575 5525);
FORCEPROP 2 LAST CDS_LIB dev_discrete
J 0
(-5625 5425);
PAINT ORANGE (-5625 5425);
DISPLAY INVISIBLE (-5625 5425);
FORCEPROP 2 LAST CDS_SEC 1
J 0
(-5575 5625);
DISPLAY 1.404255 (-5575 5625);
PAINT ORANGE (-5575 5625);
DISPLAY INVISIBLE (-5575 5625);
FORCEPROP 2 LAST $SEC 1
J 0
(-5575 5625);
DISPLAY 0.936170 (-5575 5625);
PAINT MONO (-5575 5625);
DISPLAY INVISIBLE (-5575 5625);
FORCEPROP 1 LAST PATH I20
J 0
(-5575 5575);
DISPLAY 0.978723 (-5575 5575);
PAINT WHITE (-5575 5575);
DISPLAY INVISIBLE (-5575 5575);
FORCEPROP 2 LAST ROOM MIO_CHASSIS
J 0
(-5575 5575);
DISPLAY 1.404255 (-5575 5575);
PAINT ORANGE (-5575 5575);
DISPLAY INVISIBLE (-5575 5575);
FORCEADD RES..1
(-7550 6225);
FORCEPROP 1 LAST VALUE 0.0
J 2
(-7450 6275);
DISPLAY 0.617021 (-7450 6275);
PAINT SKYBLUE (-7450 6275);
FORCEPROP 1 LASTPIN (-7650 6225) $PN 1
J 0
(-7638 6237);
DISPLAY 0.617021 (-7638 6237);
PAINT MONO (-7638 6237);
FORCEPROP 1 LAST MATERIAL CHIP
J 0
(-7500 6075);
DISPLAY 0.617021 (-7500 6075);
PAINT SKYBLUE (-7500 6075);
FORCEPROP 1 LASTPIN (-7450 6225) $PN 2
J 0
(-7488 6237);
DISPLAY 0.617021 (-7488 6237);
PAINT MONO (-7488 6237);
FORCEPROP 1 LAST PACK_TYPE 0402
J 0
(-7700 6075);
DISPLAY 0.617021 (-7700 6075);
PAINT SKYBLUE (-7700 6075);
FORCEPROP 1 LAST WATTAGE 1/16W
J 2
(-7575 6175);
DISPLAY 0.617021 (-7575 6175);
PAINT SKYBLUE (-7575 6175);
FORCEPROP 1 LAST LOCATION R1M13
J 0
(-7675 6275);
DISPLAY 0.617021 (-7675 6275);
PAINT AQUA (-7675 6275);
FORCEPROP 1 LAST PART_NUMBER G21497-005
J 0
(-8175 6150);
DISPLAY 0.617021 (-8175 6150);
PAINT BLUE (-8175 6150);
FORCEPROP 1 LAST TOLERANCE 5%
J 0
(-7500 6175);
DISPLAY 0.617021 (-7500 6175);
PAINT SKYBLUE (-7500 6175);
FORCEPROP 2 LAST CDS_LIB mstr_discrete
J 0
(-7550 6225);
DISPLAY 1.361702 (-7550 6225);
PAINT ORANGE (-7550 6225);
DISPLAY INVISIBLE (-7550 6225);
FORCEPROP 2 LAST CDS_SEC 1
J 0
(-7600 6425);
DISPLAY 1.404255 (-7600 6425);
PAINT ORANGE (-7600 6425);
DISPLAY INVISIBLE (-7600 6425);
FORCEPROP 2 LAST $SEC 1
J 0
(-7600 6425);
DISPLAY 0.936170 (-7600 6425);
PAINT MONO (-7600 6425);
DISPLAY INVISIBLE (-7600 6425);
FORCEPROP 2 LAST CDS_LOCATION R1M13
J 0
(-7675 6275);
DISPLAY 0.617021 (-7675 6275);
PAINT AQUA (-7675 6275);
DISPLAY INVISIBLE (-7675 6275);
FORCEPROP 1 LAST PATH I3
J 0
(-7600 6375);
DISPLAY 0.978723 (-7600 6375);
PAINT WHITE (-7600 6375);
DISPLAY INVISIBLE (-7600 6375);
FORCEPROP 2 LAST ROOM MIO_CHASSIS
J 0
(-7375 6325);
PAINT PEACH (-7375 6325);
DISPLAY INVISIBLE (-7375 6325);
FORCEADD GND..1
(-3825 8250);
FORCEPROP 3 LASTPIN (-3825 8300) SIG_NAME GND\g
J 0
(-3815 8310);
DISPLAY 0.659574 (-3815 8310);
PAINT MONO (-3815 8310);
DISPLAY INVISIBLE (-3815 8310);
FORCEPROP 1 LAST VOLTAGE 0
J 0
(-3825 8250);
PAINT SKYBLUE (-3825 8250);
DISPLAY INVISIBLE (-3825 8250);
FORCEPROP 2 LAST CDS_LIB mstr_symbols
J 0
(-3825 8250);
DISPLAY 1.765957 (-3825 8250);
PAINT ORANGE (-3825 8250);
DISPLAY INVISIBLE (-3825 8250);
FORCEPROP 1 LAST SIZE 1B
J 0
(-3750 8200);
DISPLAY 0.978723 (-3750 8200);
PAINT ORANGE (-3750 8200);
DISPLAY INVISIBLE (-3750 8200);
FORCEPROP 1 LAST PATH I30
J 0
(-3750 8250);
DISPLAY 0.872340 (-3750 8250);
PAINT AQUA (-3750 8250);
DISPLAY INVISIBLE (-3750 8250);
FORCEPROP 2 LAST ROOM DEBUG
J 0
(-4025 8325);
DISPLAY 0.978723 (-4025 8325);
PAINT ORANGE (-4025 8325);
DISPLAY INVISIBLE (-4025 8325);
FORCEPROP 1 LAST BODY_TYPE PLUMBING
J 0
(-3870 8207);
DISPLAY 0.340426 (-3870 8207);
PAINT GREEN (-3870 8207);
DISPLAY INVISIBLE (-3870 8207);
FORCEPROP 1 LAST HDL_POWER GND
J 0
(-3825 8400);
DISPLAY 0.978723 (-3825 8400);
PAINT GREEN (-3825 8400);
DISPLAY INVISIBLE (-3825 8400);
FORCEADD LED..2
(-3825 8475);
FORCEPROP 1 LAST LOCATION DS9A6
J 0
(-3725 8525);
DISPLAY 0.617021 (-3725 8525);
PAINT AQUA (-3725 8525);
FORCEPROP 1 LAST PART_NUMBER C97278-010
J 0
(-3725 8375);
DISPLAY 0.617021 (-3725 8375);
PAINT BLUE (-3725 8375);
FORCEPROP 1 LAST MATERIAL IC
J 0
(-3725 8425);
DISPLAY 0.617021 (-3725 8425);
PAINT SKYBLUE (-3725 8425);
FORCEPROP 1 LASTPIN (-3825 8375) $PN 2
J 0
(-3800 8350);
DISPLAY 0.617021 (-3800 8350);
PAINT MONO (-3800 8350);
FORCEPROP 1 LASTPIN (-3825 8575) $PN 1
J 0
(-3800 8550);
DISPLAY 0.617021 (-3800 8550);
PAINT MONO (-3800 8550);
FORCEPROP 1 LAST COLOR GREEN
J 0
(-3725 8475);
DISPLAY 0.617021 (-3725 8475);
PAINT BLUE (-3725 8475);
FORCEPROP 1 LAST PACK_TYPE A1LF
J 0
(-3725 8325);
PAINT SKYBLUE (-3725 8325);
DISPLAY INVISIBLE (-3725 8325);
FORCEPROP 2 LAST SEC_TYPE A1LF
J 0
(-3725 8625);
DISPLAY 1.404255 (-3725 8625);
PAINT ORANGE (-3725 8625);
DISPLAY INVISIBLE (-3725 8625);
FORCEPROP 2 LAST CDS_LIB mstr_discrete
J 0
(-3825 8475);
PAINT ORANGE (-3825 8475);
DISPLAY INVISIBLE (-3825 8475);
FORCEPROP 2 LAST SEC 1
J 0
(-3725 8625);
DISPLAY 0.936170 (-3725 8625);
PAINT MONO (-3725 8625);
DISPLAY INVISIBLE (-3725 8625);
FORCEPROP 2 LAST CDS_LOCATION DS9A6
J 0
(-3725 8525);
DISPLAY 0.617021 (-3725 8525);
PAINT AQUA (-3725 8525);
DISPLAY INVISIBLE (-3725 8525);
FORCEPROP 1 LAST PATH I31
J 0
(-3725 8575);
DISPLAY 0.978723 (-3725 8575);
PAINT BLUE (-3725 8575);
DISPLAY INVISIBLE (-3725 8575);
FORCEPROP 2 LAST ROOM MIO_CHASSIS
J 0
(-3725 8565);
DISPLAY 0.787234 (-3725 8565);
PAINT SKYBLUE (-3725 8565);
DISPLAY INVISIBLE (-3725 8565);
FORCEADD RES..2
(-3825 8850);
FORCEPROP 1 LAST LOCATION R1L37
J 0
(-3780 8975);
DISPLAY 0.617021 (-3780 8975);
PAINT AQUA (-3780 8975);
FORCEPROP 1 LAST PART_NUMBER G21796-076
J 0
(-3785 8725);
DISPLAY 0.617021 (-3785 8725);
PAINT BLUE (-3785 8725);
FORCEPROP 1 LAST VALUE 301.0
J 0
(-3780 8925);
DISPLAY 0.617021 (-3780 8925);
PAINT SKYBLUE (-3780 8925);
FORCEPROP 1 LAST TOLERANCE 1%
J 0
(-3780 8875);
DISPLAY 0.617021 (-3780 8875);
PAINT SKYBLUE (-3780 8875);
FORCEPROP 1 LAST PACK_TYPE 0402
J 0
(-3785 8675);
DISPLAY 0.617021 (-3785 8675);
PAINT SKYBLUE (-3785 8675);
FORCEPROP 1 LAST MATERIAL CHIP
J 0
(-3785 8775);
DISPLAY 0.617021 (-3785 8775);
PAINT SKYBLUE (-3785 8775);
FORCEPROP 1 LAST WATTAGE 1/16W
J 0
(-3785 8825);
DISPLAY 0.617021 (-3785 8825);
PAINT SKYBLUE (-3785 8825);
FORCEPROP 2 LAST CDS_LIB mstr_discrete
J 0
(-3825 8850);
PAINT RED (-3825 8850);
DISPLAY INVISIBLE (-3825 8850);
FORCEPROP 0 LAST SIGNAL_MODEL DEFAULT_RESISTOR_332OHM_2_1
J 0
(-3775 9075);
PAINT MONO (-3775 9075);
DISPLAY INVISIBLE (-3775 9075);
FORCEPROP 2 LAST CDS_SEC 1
J 0
(-3775 9075);
DISPLAY 1.404255 (-3775 9075);
PAINT ORANGE (-3775 9075);
DISPLAY INVISIBLE (-3775 9075);
FORCEPROP 2 LAST $SEC 1
J 0
(-3775 9075);
DISPLAY 0.936170 (-3775 9075);
PAINT MONO (-3775 9075);
DISPLAY INVISIBLE (-3775 9075);
FORCEPROP 2 LAST CDS_LOCATION R1L37
J 0
(-3780 8975);
DISPLAY 0.617021 (-3780 8975);
PAINT AQUA (-3780 8975);
DISPLAY INVISIBLE (-3780 8975);
FORCEPROP 1 LAST PATH I33
J 0
(-3775 9025);
DISPLAY 0.978723 (-3775 9025);
PAINT WHITE (-3775 9025);
DISPLAY INVISIBLE (-3775 9025);
FORCEPROP 0 LAST ROOM MIO_CHASSIS
J 0
(-3750 9025);
DISPLAY 0.978723 (-3750 9025);
PAINT ORANGE (-3750 9025);
DISPLAY INVISIBLE (-3750 9025);
FORCEPROP 1 LASTPIN (-3825 8750) $PN 2
J 0
(-3820 8760);
DISPLAY 0.936170 (-3820 8760);
PAINT MONO (-3820 8760);
DISPLAY INVISIBLE (-3820 8760);
FORCEPROP 1 LASTPIN (-3825 8950) $PN 1
J 0
(-3820 8912);
DISPLAY 0.936170 (-3820 8912);
PAINT MONO (-3820 8912);
DISPLAY INVISIBLE (-3820 8912);
FORCEADD P5V_STBY..1
(-3825 9050);
FORCEPROP 3 LASTPIN (-3825 9000) SIG_NAME P5V_STBY\g
J 0
(-3815 9010);
DISPLAY 0.659574 (-3815 9010);
PAINT MONO (-3815 9010);
DISPLAY INVISIBLE (-3815 9010);
FORCEPROP 1 LAST VOLTAGE 5.0V
J 0
(-3870 9007);
DISPLAY 0.340426 (-3870 9007);
PAINT SKYBLUE (-3870 9007);
DISPLAY INVISIBLE (-3870 9007);
FORCEPROP 2 LAST CDS_LIB mstr_symbols
J 0
(-3825 9050);
PAINT ORANGE (-3825 9050);
DISPLAY INVISIBLE (-3825 9050);
FORCEPROP 1 LAST SIZE 1B
J 0
(-3780 9072);
DISPLAY 0.340426 (-3780 9072);
PAINT GREEN (-3780 9072);
DISPLAY INVISIBLE (-3780 9072);
FORCEPROP 1 LAST PATH I36
J 0
(-3780 9052);
DISPLAY 0.340426 (-3780 9052);
PAINT GREEN (-3780 9052);
DISPLAY INVISIBLE (-3780 9052);
FORCEPROP 1 LAST BODY_TYPE PLUMBING
J 0
(-3870 9007);
DISPLAY 0.340426 (-3870 9007);
PAINT GREEN (-3870 9007);
DISPLAY INVISIBLE (-3870 9007);
FORCEPROP 1 LAST HDL_POWER P5V_STBY
J 0
(-4125 8925);
DISPLAY 0.872340 (-4125 8925);
PAINT ORANGE (-4125 8925);
DISPLAY INVISIBLE (-4125 8925);
FORCEADD OFFPAGE..1
(-8650 6325);
FORCEPROP 2 LAST $XR0 120 
J 0
(-8932 6325);
DISPLAY 0.638298 (-8932 6325);
PAINT MONO (-8932 6325);
FORCEPROP 2 LAST CDS_LIB mstr_standard
J 0
(-8650 6325);
DISPLAY 1.361702 (-8650 6325);
PAINT ORANGE (-8650 6325);
DISPLAY INVISIBLE (-8650 6325);
FORCEPROP 2 LAST ROOM MIO_CHASSIS
J 0
(-8850 6375);
DISPLAY 1.404255 (-8850 6375);
PAINT ORANGE (-8850 6375);
DISPLAY INVISIBLE (-8850 6375);
FORCEPROP 2 LAST PATH I4
J 0
(-8900 6375);
DISPLAY 1.021277 (-8900 6375);
PAINT ORANGE (-8900 6375);
DISPLAY INVISIBLE (-8900 6375);
FORCEPROP 1 LAST OFFPAGE TRUE
J 0
(-8325 6200);
PAINT GREEN (-8325 6200);
DISPLAY INVISIBLE (-8325 6200);
FORCEPROP 1 LAST COMMENT_BODY TRUE
J 0
(-8525 6225);
DISPLAY 1.170213 (-8525 6225);
PAINT GREEN (-8525 6225);
DISPLAY INVISIBLE (-8525 6225);
FORCEADD LED..3
(-5550 6275);
FORCEPROP 1 LAST LOCATION DS9A2
J 0
(-5650 6475);
DISPLAY 0.617021 (-5650 6475);
PAINT AQUA (-5650 6475);
FORCEPROP 1 LAST PART_NUMBER C96565-011
J 0
(-5650 6125);
DISPLAY 0.617021 (-5650 6125);
PAINT BLUE (-5650 6125);
FORCEPROP 1 LAST MATERIAL IC
J 0
(-5650 6425);
DISPLAY 0.617021 (-5650 6425);
PAINT SKYBLUE (-5650 6425);
FORCEPROP 2 LASTPIN (-5650 6275) $PN 1
J 2
(-5660 6285);
DISPLAY 0.617021 (-5660 6285);
PAINT ORANGE (-5660 6285);
FORCEPROP 2 LASTPIN (-5450 6275) $PN 2
J 0
(-5440 6285);
DISPLAY 0.617021 (-5440 6285);
PAINT ORANGE (-5440 6285);
FORCEPROP 1 LAST COLOR GREEN
J 0
(-5650 6375);
DISPLAY 0.617021 (-5650 6375);
PAINT BLUE (-5650 6375);
FORCEPROP 1 LAST PACK_TYPE 1NCLF
J 0
(-5650 6525);
DISPLAY 0.978723 (-5650 6525);
PAINT SKYBLUE (-5650 6525);
DISPLAY INVISIBLE (-5650 6525);
FORCEPROP 2 LAST SEC_TYPE 1NCLF
J 0
(-5650 6525);
DISPLAY 1.021277 (-5650 6525);
PAINT ORANGE (-5650 6525);
DISPLAY INVISIBLE (-5650 6525);
FORCEPROP 2 LAST CDS_LIB mstr_discrete
J 0
(-5550 6275);
PAINT MONO (-5550 6275);
DISPLAY INVISIBLE (-5550 6275);
FORCEPROP 2 LAST SEC 1
J 0
(-5650 6525);
DISPLAY 0.680851 (-5650 6525);
PAINT MONO (-5650 6525);
DISPLAY INVISIBLE (-5650 6525);
FORCEPROP 2 LAST CDS_LOCATION DS9A2
J 0
(-5650 6475);
DISPLAY 0.617021 (-5650 6475);
PAINT AQUA (-5650 6475);
DISPLAY INVISIBLE (-5650 6475);
FORCEPROP 1 LAST PATH I42
J 0
(-5200 6425);
DISPLAY 0.978723 (-5200 6425);
PAINT BLUE (-5200 6425);
DISPLAY INVISIBLE (-5200 6425);
FORCEPROP 0 LAST ROOM MIO_CHASSIS
J 0
(-5650 6575);
DISPLAY 1.021277 (-5650 6575);
PAINT ORANGE (-5650 6575);
DISPLAY INVISIBLE (-5650 6575);
FORCEADD RES..2
(-4675 6600);
FORCEPROP 1 LAST LOCATION R1L21
J 0
(-4630 6725);
DISPLAY 0.617021 (-4630 6725);
PAINT AQUA (-4630 6725);
FORCEPROP 1 LAST PART_NUMBER G21796-298
J 0
(-4635 6475);
DISPLAY 0.617021 (-4635 6475);
PAINT BLUE (-4635 6475);
FORCEPROP 1 LAST VALUE 64.9
J 0
(-4630 6675);
DISPLAY 0.617021 (-4630 6675);
PAINT SKYBLUE (-4630 6675);
FORCEPROP 1 LAST TOLERANCE 1.0%
J 0
(-4630 6625);
DISPLAY 0.617021 (-4630 6625);
PAINT SKYBLUE (-4630 6625);
FORCEPROP 1 LAST PACK_TYPE 0402
J 0
(-4635 6425);
DISPLAY 0.617021 (-4635 6425);
PAINT SKYBLUE (-4635 6425);
FORCEPROP 1 LAST MATERIAL CHIP
J 0
(-4635 6525);
DISPLAY 0.617021 (-4635 6525);
PAINT SKYBLUE (-4635 6525);
FORCEPROP 1 LAST WATTAGE 1/16W
J 0
(-4635 6575);
DISPLAY 0.617021 (-4635 6575);
PAINT SKYBLUE (-4635 6575);
FORCEPROP 1 LASTPIN (-4675 6500) $PN 2
J 0
(-4670 6510);
DISPLAY 0.617021 (-4670 6510);
PAINT ORANGE (-4670 6510);
FORCEPROP 1 LASTPIN (-4675 6700) $PN 1
J 0
(-4670 6662);
DISPLAY 0.617021 (-4670 6662);
PAINT ORANGE (-4670 6662);
FORCEPROP 2 LAST CDS_LIB mstr_discrete
J 0
(-4675 6600);
PAINT MONO (-4675 6600);
DISPLAY INVISIBLE (-4675 6600);
FORCEPROP 2 LAST SEC_TYPE 0402
J 0
(-4625 6825);
DISPLAY 1.021277 (-4625 6825);
PAINT ORANGE (-4625 6825);
DISPLAY INVISIBLE (-4625 6825);
FORCEPROP 2 LAST SEC 1
J 0
(-4625 6825);
DISPLAY 0.680851 (-4625 6825);
PAINT MONO (-4625 6825);
DISPLAY INVISIBLE (-4625 6825);
FORCEPROP 2 LAST CDS_LOCATION R1L21
J 0
(-4630 6725);
DISPLAY 0.617021 (-4630 6725);
PAINT AQUA (-4630 6725);
DISPLAY INVISIBLE (-4630 6725);
FORCEPROP 1 LAST PATH I43
J 0
(-4625 6775);
DISPLAY 0.978723 (-4625 6775);
PAINT WHITE (-4625 6775);
DISPLAY INVISIBLE (-4625 6775);
FORCEPROP 0 LAST ROOM MIO_CHASSIS
J 0
(-4625 6825);
DISPLAY 1.021277 (-4625 6825);
PAINT ORANGE (-4625 6825);
DISPLAY INVISIBLE (-4625 6825);
FORCEADD P3V3..1
(-5625 5725);
FORCEPROP 3 LASTPIN (-5625 5675) SIG_NAME P3V3\g
J 0
(-5615 5685);
DISPLAY 0.659574 (-5615 5685);
PAINT MONO (-5615 5685);
DISPLAY INVISIBLE (-5615 5685);
FORCEPROP 1 LAST VOLTAGE +3.3
J 0
(-5625 5725);
PAINT SKYBLUE (-5625 5725);
DISPLAY INVISIBLE (-5625 5725);
FORCEPROP 2 LAST CDS_LIB mstr_symbols
J 0
(-5625 5725);
PAINT ORANGE (-5625 5725);
DISPLAY INVISIBLE (-5625 5725);
FORCEPROP 1 LAST SIZE 1B
J 0
(-5580 5747);
DISPLAY 0.553191 (-5580 5747);
PAINT GREEN (-5580 5747);
DISPLAY INVISIBLE (-5580 5747);
FORCEPROP 1 LAST PATH I45
J 0
(-5580 5727);
DISPLAY 0.340426 (-5580 5727);
PAINT GREEN (-5580 5727);
DISPLAY INVISIBLE (-5580 5727);
FORCEPROP 2 LAST ROOM SM_CONTROLLER
J 0
(-6150 5825);
DISPLAY 1.404255 (-6150 5825);
PAINT ORANGE (-6150 5825);
DISPLAY INVISIBLE (-6150 5825);
FORCEPROP 1 LAST BODY_TYPE PLUMBING
J 0
(-5670 5682);
DISPLAY 0.468085 (-5670 5682);
PAINT GREEN (-5670 5682);
DISPLAY INVISIBLE (-5670 5682);
FORCEPROP 1 LAST HDL_POWER P3V3
J 0
(-5950 5600);
DISPLAY 1.170213 (-5950 5600);
PAINT GREEN (-5950 5600);
DISPLAY INVISIBLE (-5950 5600);
FORCEADD GND..1
(-5625 5075);
FORCEPROP 3 LASTPIN (-5625 5125) SIG_NAME GND\g
J 0
(-5615 5135);
DISPLAY 0.659574 (-5615 5135);
PAINT MONO (-5615 5135);
DISPLAY INVISIBLE (-5615 5135);
FORCEPROP 1 LAST VOLTAGE 0
J 0
(-5625 5075);
PAINT SKYBLUE (-5625 5075);
DISPLAY INVISIBLE (-5625 5075);
FORCEPROP 2 LAST CDS_LIB mstr_symbols
J 0
(-5625 5075);
PAINT ORANGE (-5625 5075);
DISPLAY INVISIBLE (-5625 5075);
FORCEPROP 1 LAST SIZE 1B
J 0
(-5550 5025);
DISPLAY 1.212766 (-5550 5025);
PAINT GREEN (-5550 5025);
DISPLAY INVISIBLE (-5550 5025);
FORCEPROP 1 LAST PATH I46
J 0
(-5550 5075);
DISPLAY 0.872340 (-5550 5075);
PAINT AQUA (-5550 5075);
DISPLAY INVISIBLE (-5550 5075);
FORCEPROP 2 LAST ROOM MIO_CHASSIS
J 0
(-6150 5150);
DISPLAY 1.404255 (-6150 5150);
PAINT ORANGE (-6150 5150);
DISPLAY INVISIBLE (-6150 5150);
FORCEPROP 1 LAST BODY_TYPE PLUMBING
J 0
(-5670 5032);
DISPLAY 0.340426 (-5670 5032);
PAINT GREEN (-5670 5032);
DISPLAY INVISIBLE (-5670 5032);
FORCEPROP 1 LAST HDL_POWER GND
J 0
(-5625 5225);
DISPLAY 1.212766 (-5625 5225);
PAINT GREEN (-5625 5225);
DISPLAY INVISIBLE (-5625 5225);
FORCEADD RES..1
(-7750 6325);
FORCEPROP 1 LAST PART_NUMBER G21497-005
J 0
(-8075 6275);
DISPLAY 0.617021 (-8075 6275);
PAINT BLUE (-8075 6275);
FORCEPROP 1 LAST VALUE 0.0
J 2
(-8000 6425);
DISPLAY 0.617021 (-8000 6425);
PAINT SKYBLUE (-8000 6425);
FORCEPROP 1 LAST TOLERANCE 5%
J 0
(-7950 6425);
DISPLAY 0.617021 (-7950 6425);
PAINT SKYBLUE (-7950 6425);
FORCEPROP 1 LAST MATERIAL CHIP
J 0
(-8050 6350);
DISPLAY 0.617021 (-8050 6350);
PAINT SKYBLUE (-8050 6350);
FORCEPROP 1 LASTPIN (-7850 6325) $PN 1
J 0
(-7838 6337);
DISPLAY 0.617021 (-7838 6337);
PAINT MONO (-7838 6337);
FORCEPROP 1 LAST LOCATION R1M10
J 0
(-7825 6375);
DISPLAY 0.617021 (-7825 6375);
PAINT AQUA (-7825 6375);
FORCEPROP 1 LAST PACK_TYPE 0402
J 0
(-7600 6375);
DISPLAY 0.617021 (-7600 6375);
PAINT SKYBLUE (-7600 6375);
FORCEPROP 1 LAST WATTAGE 1/16W
J 2
(-7525 6425);
DISPLAY 0.617021 (-7525 6425);
PAINT SKYBLUE (-7525 6425);
FORCEPROP 1 LASTPIN (-7650 6325) $PN 2
J 0
(-7688 6337);
DISPLAY 0.617021 (-7688 6337);
PAINT MONO (-7688 6337);
FORCEPROP 2 LAST CDS_LIB mstr_discrete
J 0
(-7750 6325);
DISPLAY 1.361702 (-7750 6325);
PAINT ORANGE (-7750 6325);
DISPLAY INVISIBLE (-7750 6325);
FORCEPROP 2 LAST CDS_SEC 1
J 0
(-7800 6525);
DISPLAY 1.404255 (-7800 6525);
PAINT ORANGE (-7800 6525);
DISPLAY INVISIBLE (-7800 6525);
FORCEPROP 2 LAST $SEC 1
J 0
(-7800 6525);
DISPLAY 0.936170 (-7800 6525);
PAINT MONO (-7800 6525);
DISPLAY INVISIBLE (-7800 6525);
FORCEPROP 2 LAST CDS_LOCATION R1M10
J 0
(-7825 6375);
DISPLAY 0.617021 (-7825 6375);
PAINT AQUA (-7825 6375);
DISPLAY INVISIBLE (-7825 6375);
FORCEPROP 1 LAST PATH I6
J 0
(-7800 6475);
DISPLAY 0.978723 (-7800 6475);
PAINT WHITE (-7800 6475);
DISPLAY INVISIBLE (-7800 6475);
FORCEPROP 2 LAST ROOM MIO_CHASSIS
J 0
(-7575 6425);
DISPLAY 1.404255 (-7575 6425);
PAINT ORANGE (-7575 6425);
DISPLAY INVISIBLE (-7575 6425);
FORCEADD TTL1G08..1
(-6550 6275);
FORCEPROP 1 LAST POWER_GROUP VCC=P3V3;GND=GND;
J 1
(-6525 6100);
DISPLAY 0.617021 (-6525 6100);
PAINT ORANGE (-6525 6100);
FORCEPROP 1 LAST LOCATION U1M1
J 0
(-6650 6500);
DISPLAY 0.617021 (-6650 6500);
PAINT AQUA (-6650 6500);
FORCEPROP 1 LAST VALUE NC7SZ08
J 1
(-6550 6150);
DISPLAY 0.617021 (-6550 6150);
PAINT SKYBLUE (-6550 6150);
FORCEPROP 1 LAST MATERIAL IC
J 1
(-6575 6485);
DISPLAY 0.617021 (-6575 6485);
PAINT SKYBLUE (-6575 6485);
FORCEPROP 2 LASTPIN (-6400 6275) $PN 4
J 0
(-6390 6285);
DISPLAY 0.617021 (-6390 6285);
PAINT ORANGE (-6390 6285);
FORCEPROP 2 LASTPIN (-6700 6225) $PN 2
J 2
(-6710 6235);
DISPLAY 0.617021 (-6710 6235);
PAINT ORANGE (-6710 6235);
FORCEPROP 2 LASTPIN (-6700 6325) $PN 1
J 2
(-6710 6335);
DISPLAY 0.617021 (-6710 6335);
PAINT ORANGE (-6710 6335);
FORCEPROP 1 LAST PACK_TYPE SOTLF
J 1
(-6575 6450);
DISPLAY 0.617021 (-6575 6450);
PAINT SKYBLUE (-6575 6450);
FORCEPROP 1 LAST PART_NUMBER D10321-001
J 1
(-6575 6375);
DISPLAY 0.617021 (-6575 6375);
PAINT BLUE (-6575 6375);
FORCEPROP 2 LAST CDS_LIB mstr_ttl
J 0
(-6550 6275);
PAINT MONO (-6550 6275);
DISPLAY INVISIBLE (-6550 6275);
FORCEPROP 2 LAST SEC_TYPE SOTLF
J 0
(-6550 6575);
DISPLAY 1.021277 (-6550 6575);
PAINT ORANGE (-6550 6575);
DISPLAY INVISIBLE (-6550 6575);
FORCEPROP 0 LAST BOM_COST MIO_CHASSIS
J 0
(-6650 6700);
DISPLAY 1.021277 (-6650 6700);
PAINT ORANGE (-6650 6700);
DISPLAY INVISIBLE (-6650 6700);
FORCEPROP 2 LAST SEC 1
J 0
(-6550 6575);
DISPLAY 0.680851 (-6550 6575);
PAINT MONO (-6550 6575);
DISPLAY INVISIBLE (-6550 6575);
FORCEPROP 2 LAST CDS_LOCATION U1M1
J 0
(-6650 6500);
DISPLAY 0.617021 (-6650 6500);
PAINT AQUA (-6650 6500);
DISPLAY INVISIBLE (-6650 6500);
FORCEPROP 1 LAST PATH I70
J 1
(-6570 6540);
DISPLAY 0.702128 (-6570 6540);
PAINT WHITE (-6570 6540);
DISPLAY INVISIBLE (-6570 6540);
FORCEPROP 0 LAST ROOM MIO_CHASSIS
J 0
(-6650 6600);
DISPLAY 1.021277 (-6650 6600);
PAINT ORANGE (-6650 6600);
DISPLAY INVISIBLE (-6650 6600);
FORCEADD LED..2
(-7200 8475);
FORCEPROP 1 LAST LOCATION DS9F1
J 0
(-7100 8525);
DISPLAY 0.617021 (-7100 8525);
PAINT AQUA (-7100 8525);
FORCEPROP 1 LAST PART_NUMBER D14725-005
J 0
(-7100 8375);
DISPLAY 0.617021 (-7100 8375);
PAINT BLUE (-7100 8375);
FORCEPROP 1 LAST MATERIAL IC
J 0
(-7100 8425);
DISPLAY 0.617021 (-7100 8425);
PAINT SKYBLUE (-7100 8425);
FORCEPROP 1 LASTPIN (-7200 8375) $PN 2
J 0
(-7175 8350);
DISPLAY 0.617021 (-7175 8350);
PAINT BLUE (-7175 8350);
FORCEPROP 1 LASTPIN (-7200 8575) $PN 1
J 0
(-7175 8550);
DISPLAY 0.617021 (-7175 8550);
PAINT BLUE (-7175 8550);
FORCEPROP 1 LAST COLOR RED
J 0
(-7100 8475);
DISPLAY 0.617021 (-7100 8475);
PAINT BLUE (-7100 8475);
FORCEPROP 1 LAST PACK_TYPE A1
J 0
(-7100 8325);
DISPLAY 0.978723 (-7100 8325);
PAINT SKYBLUE (-7100 8325);
DISPLAY INVISIBLE (-7100 8325);
FORCEPROP 2 LAST SEC_TYPE A1
J 0
(-7100 8625);
DISPLAY 1.021277 (-7100 8625);
PAINT ORANGE (-7100 8625);
DISPLAY INVISIBLE (-7100 8625);
FORCEPROP 2 LAST CDS_LIB mstr_discrete
J 0
(-7200 8475);
PAINT ORANGE (-7200 8475);
DISPLAY INVISIBLE (-7200 8475);
FORCEPROP 0 LAST BOM_COST SM_CONTROLLER
J 0
(-7100 8725);
DISPLAY 1.021277 (-7100 8725);
PAINT ORANGE (-7100 8725);
DISPLAY INVISIBLE (-7100 8725);
FORCEPROP 2 LAST SEC 1
J 0
(-7100 8625);
DISPLAY 0.680851 (-7100 8625);
PAINT MONO (-7100 8625);
DISPLAY INVISIBLE (-7100 8625);
FORCEPROP 2 LAST CDS_LOCATION DS9F1
J 0
(-7100 8525);
DISPLAY 0.617021 (-7100 8525);
PAINT AQUA (-7100 8525);
DISPLAY INVISIBLE (-7100 8525);
FORCEPROP 1 LAST PATH I71
J 0
(-7100 8575);
DISPLAY 0.978723 (-7100 8575);
PAINT BLUE (-7100 8575);
DISPLAY INVISIBLE (-7100 8575);
FORCEPROP 0 LAST ROOM BMC
J 0
(-7100 8625);
DISPLAY 1.021277 (-7100 8625);
PAINT ORANGE (-7100 8625);
DISPLAY INVISIBLE (-7100 8625);
FORCEADD RES..2
(-7200 8825);
FORCEPROP 1 LAST LOCATION R9F28
J 0
(-7155 8950);
DISPLAY 0.617021 (-7155 8950);
PAINT AQUA (-7155 8950);
FORCEPROP 1 LAST PART_NUMBER G21796-271
J 0
(-7160 8700);
DISPLAY 0.617021 (-7160 8700);
PAINT BLUE (-7160 8700);
FORCEPROP 1 LAST VALUE 221
J 0
(-7155 8900);
DISPLAY 0.617021 (-7155 8900);
PAINT SKYBLUE (-7155 8900);
FORCEPROP 1 LAST TOLERANCE 1.0%
J 0
(-7155 8850);
DISPLAY 0.617021 (-7155 8850);
PAINT SKYBLUE (-7155 8850);
FORCEPROP 1 LAST PACK_TYPE 0402
J 0
(-7160 8650);
DISPLAY 0.617021 (-7160 8650);
PAINT SKYBLUE (-7160 8650);
FORCEPROP 1 LAST MATERIAL CHIP
J 0
(-7160 8750);
DISPLAY 0.617021 (-7160 8750);
PAINT SKYBLUE (-7160 8750);
FORCEPROP 1 LAST WATTAGE 1/16W
J 0
(-7160 8800);
DISPLAY 0.617021 (-7160 8800);
PAINT SKYBLUE (-7160 8800);
FORCEPROP 1 LASTPIN (-7200 8725) $PN 2
J 0
(-7195 8735);
DISPLAY 0.617021 (-7195 8735);
PAINT ORANGE (-7195 8735);
FORCEPROP 1 LASTPIN (-7200 8925) $PN 1
J 0
(-7195 8887);
DISPLAY 0.617021 (-7195 8887);
PAINT ORANGE (-7195 8887);
FORCEPROP 2 LAST SEC_TYPE 0402
J 0
(-7150 9050);
DISPLAY 1.021277 (-7150 9050);
PAINT ORANGE (-7150 9050);
DISPLAY INVISIBLE (-7150 9050);
FORCEPROP 2 LAST CDS_LIB mstr_discrete
J 0
(-7200 8825);
PAINT MONO (-7200 8825);
DISPLAY INVISIBLE (-7200 8825);
FORCEPROP 0 LAST BOM_COST SM_CONTROLLER
J 0
(-7150 9150);
DISPLAY 1.021277 (-7150 9150);
PAINT ORANGE (-7150 9150);
DISPLAY INVISIBLE (-7150 9150);
FORCEPROP 2 LAST SEC 1
J 0
(-7150 9050);
DISPLAY 0.680851 (-7150 9050);
PAINT MONO (-7150 9050);
DISPLAY INVISIBLE (-7150 9050);
FORCEPROP 2 LAST CDS_LOCATION R9F28
J 0
(-7155 8950);
DISPLAY 0.617021 (-7155 8950);
PAINT AQUA (-7155 8950);
DISPLAY INVISIBLE (-7155 8950);
FORCEPROP 1 LAST PATH I72
J 0
(-7150 9000);
DISPLAY 0.978723 (-7150 9000);
PAINT WHITE (-7150 9000);
DISPLAY INVISIBLE (-7150 9000);
FORCEPROP 0 LAST ROOM BMC
J 0
(-7150 9050);
DISPLAY 1.021277 (-7150 9050);
PAINT ORANGE (-7150 9050);
DISPLAY INVISIBLE (-7150 9050);
FORCEADD GND..1
(-7200 7650);
FORCEPROP 3 LASTPIN (-7200 7700) SIG_NAME GND\g
J 0
(-7190 7710);
DISPLAY 0.659574 (-7190 7710);
PAINT MONO (-7190 7710);
DISPLAY INVISIBLE (-7190 7710);
FORCEPROP 1 LAST VOLTAGE 0.0V
J 0
(-7245 7607);
DISPLAY 0.340426 (-7245 7607);
PAINT SKYBLUE (-7245 7607);
DISPLAY INVISIBLE (-7245 7607);
FORCEPROP 1 LAST SIZE 1B
J 0
(-7125 7600);
DISPLAY 0.872340 (-7125 7600);
PAINT AQUA (-7125 7600);
DISPLAY INVISIBLE (-7125 7600);
FORCEPROP 2 LAST CDS_LIB mstr_symbols
J 0
(-7200 7650);
PAINT MONO (-7200 7650);
DISPLAY INVISIBLE (-7200 7650);
FORCEPROP 1 LAST PATH I74
J 0
(-7125 7650);
DISPLAY 0.872340 (-7125 7650);
PAINT AQUA (-7125 7650);
DISPLAY INVISIBLE (-7125 7650);
FORCEPROP 1 LAST BODY_TYPE PLUMBING
J 0
(-7245 7607);
DISPLAY 0.340426 (-7245 7607);
PAINT GREEN (-7245 7607);
DISPLAY INVISIBLE (-7245 7607);
FORCEPROP 1 LAST HDL_POWER GND
J 0
(-7200 7800);
DISPLAY 0.872340 (-7200 7800);
PAINT GREEN (-7200 7800);
DISPLAY INVISIBLE (-7200 7800);
FORCEADD RES..2
(-8475 7850);
FORCEPROP 1 LAST LOCATION R9F30
J 0
(-8430 7975);
DISPLAY 0.617021 (-8430 7975);
PAINT AQUA (-8430 7975);
FORCEPROP 1 LAST PART_NUMBER G21796-072
J 0
(-8435 7725);
DISPLAY 0.617021 (-8435 7725);
PAINT BLUE (-8435 7725);
FORCEPROP 1 LAST VALUE 4.75K
J 0
(-8430 7925);
DISPLAY 0.617021 (-8430 7925);
PAINT SKYBLUE (-8430 7925);
FORCEPROP 1 LAST TOLERANCE 1%
J 0
(-8430 7875);
DISPLAY 0.617021 (-8430 7875);
PAINT SKYBLUE (-8430 7875);
FORCEPROP 1 LAST PACK_TYPE 0402
J 0
(-8435 7675);
DISPLAY 0.617021 (-8435 7675);
PAINT SKYBLUE (-8435 7675);
FORCEPROP 1 LAST MATERIAL CHIP
J 0
(-8435 7775);
DISPLAY 0.617021 (-8435 7775);
PAINT SKYBLUE (-8435 7775);
FORCEPROP 1 LAST WATTAGE 1/16W
J 0
(-8435 7825);
DISPLAY 0.617021 (-8435 7825);
PAINT SKYBLUE (-8435 7825);
FORCEPROP 1 LASTPIN (-8475 7750) $PN 2
J 0
(-8470 7760);
DISPLAY 0.617021 (-8470 7760);
PAINT ORANGE (-8470 7760);
FORCEPROP 1 LASTPIN (-8475 7950) $PN 1
J 0
(-8470 7912);
DISPLAY 0.617021 (-8470 7912);
PAINT ORANGE (-8470 7912);
FORCEPROP 0 LAST BOM_COST SM_CONTROLLER
J 0
(-8425 8175);
DISPLAY 1.021277 (-8425 8175);
PAINT ORANGE (-8425 8175);
DISPLAY INVISIBLE (-8425 8175);
FORCEPROP 2 LAST CDS_LIB mstr_discrete
J 0
(-8475 7850);
PAINT MONO (-8475 7850);
DISPLAY INVISIBLE (-8475 7850);
FORCEPROP 2 LAST SEC_TYPE 0402
J 0
(-8425 8075);
DISPLAY 1.021277 (-8425 8075);
PAINT ORANGE (-8425 8075);
DISPLAY INVISIBLE (-8425 8075);
FORCEPROP 2 LAST SEC 1
J 0
(-8425 8075);
DISPLAY 0.680851 (-8425 8075);
PAINT MONO (-8425 8075);
DISPLAY INVISIBLE (-8425 8075);
FORCEPROP 2 LAST CDS_LOCATION R9F30
J 0
(-8430 7975);
DISPLAY 0.617021 (-8430 7975);
PAINT AQUA (-8430 7975);
DISPLAY INVISIBLE (-8430 7975);
FORCEPROP 1 LAST PATH I76
J 0
(-8425 8025);
DISPLAY 0.978723 (-8425 8025);
PAINT WHITE (-8425 8025);
DISPLAY INVISIBLE (-8425 8025);
FORCEPROP 0 LAST ROOM BMC
J 0
(-8425 8075);
DISPLAY 1.021277 (-8425 8075);
PAINT ORANGE (-8425 8075);
DISPLAY INVISIBLE (-8425 8075);
FORCEADD P3V3_STBY..1
(-8475 8125);
FORCEPROP 3 LASTPIN (-8475 8075) SIG_NAME P3V3_STBY\g
J 0
(-8465 8085);
DISPLAY 0.659574 (-8465 8085);
PAINT MONO (-8465 8085);
DISPLAY INVISIBLE (-8465 8085);
FORCEPROP 1 LAST VOLTAGE 3.3V
J 0
(-8520 8082);
DISPLAY 0.340426 (-8520 8082);
PAINT SKYBLUE (-8520 8082);
DISPLAY INVISIBLE (-8520 8082);
FORCEPROP 2 LAST CDS_LIB mstr_symbols
J 0
(-8475 8125);
PAINT MONO (-8475 8125);
DISPLAY INVISIBLE (-8475 8125);
FORCEPROP 1 LAST SIZE 1B
J 0
(-8430 8147);
DISPLAY 0.340426 (-8430 8147);
PAINT GREEN (-8430 8147);
DISPLAY INVISIBLE (-8430 8147);
FORCEPROP 1 LAST PATH I77
J 0
(-8430 8127);
DISPLAY 0.340426 (-8430 8127);
PAINT GREEN (-8430 8127);
DISPLAY INVISIBLE (-8430 8127);
FORCEPROP 1 LAST BODY_TYPE PLUMBING
J 0
(-8520 8082);
DISPLAY 0.340426 (-8520 8082);
PAINT GREEN (-8520 8082);
DISPLAY INVISIBLE (-8520 8082);
FORCEPROP 1 LAST HDL_POWER P3V3_STBY
J 0
(-8775 8000);
DISPLAY 0.872340 (-8775 8000);
PAINT ORANGE (-8775 8000);
DISPLAY INVISIBLE (-8775 8000);
FORCEADD P3V3_STBY..1
(-7200 9125);
FORCEPROP 3 LASTPIN (-7200 9075) SIG_NAME P3V3_STBY\g
J 0
(-7190 9085);
DISPLAY 0.659574 (-7190 9085);
PAINT MONO (-7190 9085);
DISPLAY INVISIBLE (-7190 9085);
FORCEPROP 1 LAST VOLTAGE 3.3V
J 0
(-7245 9082);
DISPLAY 0.340426 (-7245 9082);
PAINT SKYBLUE (-7245 9082);
DISPLAY INVISIBLE (-7245 9082);
FORCEPROP 1 LAST SIZE 1B
J 0
(-7155 9147);
DISPLAY 0.340426 (-7155 9147);
PAINT GREEN (-7155 9147);
DISPLAY INVISIBLE (-7155 9147);
FORCEPROP 2 LAST CDS_LIB mstr_symbols
J 0
(-7200 9125);
PAINT MONO (-7200 9125);
DISPLAY INVISIBLE (-7200 9125);
FORCEPROP 1 LAST PATH I78
J 0
(-7155 9127);
DISPLAY 0.340426 (-7155 9127);
PAINT GREEN (-7155 9127);
DISPLAY INVISIBLE (-7155 9127);
FORCEPROP 1 LAST BODY_TYPE PLUMBING
J 0
(-7245 9082);
DISPLAY 0.340426 (-7245 9082);
PAINT GREEN (-7245 9082);
DISPLAY INVISIBLE (-7245 9082);
FORCEPROP 1 LAST HDL_POWER P3V3_STBY
J 0
(-7500 9000);
DISPLAY 0.872340 (-7500 9000);
PAINT ORANGE (-7500 9000);
DISPLAY INVISIBLE (-7500 9000);
FORCEADD FET_N_DUAL..5
(-7200 8050);
FORCEPROP 1 LAST LOCATION Q9F1
J 0
(-7000 8050);
DISPLAY 0.617021 (-7000 8050);
PAINT AQUA (-7000 8050);
FORCEPROP 1 LAST PART_NUMBER E40049-001
J 0
(-7000 7850);
DISPLAY 0.617021 (-7000 7850);
PAINT BLUE (-7000 7850);
FORCEPROP 1 LAST VALUE NTJD4001N
J 0
(-7000 8000);
DISPLAY 0.617021 (-7000 8000);
PAINT SKYBLUE (-7000 8000);
FORCEPROP 1 LAST MATERIAL FET
J 0
(-7000 7950);
DISPLAY 0.617021 (-7000 7950);
PAINT SKYBLUE (-7000 7950);
FORCEPROP 1 LASTPIN (-7200 7850) $PN 4
J 2
(-7142 7850);
DISPLAY 0.617021 (-7142 7850);
PAINT WHITE (-7142 7850);
FORCEPROP 1 LASTPIN (-7400 7950) $PN 5
J 2
(-7397 7965);
DISPLAY 0.617021 (-7397 7965);
PAINT WHITE (-7397 7965);
FORCEPROP 1 LASTPIN (-7200 8250) $PN 3
J 2
(-7147 8215);
DISPLAY 0.617021 (-7147 8215);
PAINT WHITE (-7147 8215);
FORCEPROP 1 LAST PACK_TYPE SMLF
J 0
(-7000 7900);
DISPLAY 0.978723 (-7000 7900);
PAINT SKYBLUE (-7000 7900);
DISPLAY INVISIBLE (-7000 7900);
FORCEPROP 2 LAST CDS_LIB mstr_discrete
J 0
(-7200 8050);
PAINT MONO (-7200 8050);
DISPLAY INVISIBLE (-7200 8050);
FORCEPROP 0 LAST BOM_COST SM_CONTROLLER
J 0
(-7000 8250);
DISPLAY 1.021277 (-7000 8250);
PAINT ORANGE (-7000 8250);
DISPLAY INVISIBLE (-7000 8250);
FORCEPROP 2 LAST SEC_TYPE SMLF
J 0
(-7000 8150);
DISPLAY 1.021277 (-7000 8150);
PAINT ORANGE (-7000 8150);
DISPLAY INVISIBLE (-7000 8150);
FORCEPROP 2 LAST SEC 2
J 0
(-7000 8150);
DISPLAY 0.680851 (-7000 8150);
PAINT MONO (-7000 8150);
DISPLAY INVISIBLE (-7000 8150);
FORCEPROP 2 LAST CDS_LOCATION Q9F1
J 0
(-7000 8050);
DISPLAY 0.617021 (-7000 8050);
PAINT AQUA (-7000 8050);
DISPLAY INVISIBLE (-7000 8050);
FORCEPROP 1 LAST PATH I79
J 0
(-7000 8100);
DISPLAY 0.978723 (-7000 8100);
PAINT BLUE (-7000 8100);
DISPLAY INVISIBLE (-7000 8100);
FORCEPROP 0 LAST ROOM BMC
J 0
(-7000 8150);
DISPLAY 1.021277 (-7000 8150);
PAINT ORANGE (-7000 8150);
DISPLAY INVISIBLE (-7000 8150);
FORCEADD RES..2
(-6975 6550);
FORCEPROP 1 LAST LOCATION R1M12
J 0
(-6930 6675);
DISPLAY 0.617021 (-6930 6675);
PAINT AQUA (-6930 6675);
FORCEPROP 1 LAST VALUE 10.0K
J 0
(-6930 6625);
DISPLAY 0.617021 (-6930 6625);
PAINT SKYBLUE (-6930 6625);
FORCEPROP 1 LAST TOLERANCE 1%
J 0
(-6930 6575);
DISPLAY 0.617021 (-6930 6575);
PAINT SKYBLUE (-6930 6575);
FORCEPROP 1 LAST PACK_TYPE 0402
J 0
(-6935 6375);
DISPLAY 0.617021 (-6935 6375);
PAINT SKYBLUE (-6935 6375);
FORCEPROP 1 LAST WATTAGE 1/16W
J 0
(-6935 6525);
DISPLAY 0.617021 (-6935 6525);
PAINT SKYBLUE (-6935 6525);
FORCEPROP 1 LASTPIN (-6975 6450) $PN 2
J 0
(-6970 6460);
DISPLAY 0.617021 (-6970 6460);
PAINT MONO (-6970 6460);
FORCEPROP 1 LASTPIN (-6975 6650) $PN 1
J 0
(-6970 6612);
DISPLAY 0.617021 (-6970 6612);
PAINT MONO (-6970 6612);
FORCEPROP 1 LAST PART_NUMBER G21796-016
J 0
(-6935 6425);
DISPLAY 0.617021 (-6935 6425);
PAINT BLUE (-6935 6425);
FORCEPROP 1 LAST MATERIAL CHIP
J 0
(-6935 6475);
DISPLAY 0.617021 (-6935 6475);
PAINT SKYBLUE (-6935 6475);
FORCEPROP 2 LAST SEC_TYPE 0402
J 0
(-6925 6775);
DISPLAY 1.361702 (-6925 6775);
PAINT MONO (-6925 6775);
DISPLAY INVISIBLE (-6925 6775);
FORCEPROP 2 LAST CDS_LIB mstr_discrete
J 0
(-6975 6550);
DISPLAY 1.361702 (-6975 6550);
PAINT ORANGE (-6975 6550);
DISPLAY INVISIBLE (-6975 6550);
FORCEPROP 2 LAST SEC 1
J 0
(-6925 6775);
DISPLAY 0.936170 (-6925 6775);
PAINT MONO (-6925 6775);
DISPLAY INVISIBLE (-6925 6775);
FORCEPROP 2 LAST CDS_LOCATION R1M12
J 0
(-6930 6675);
DISPLAY 0.617021 (-6930 6675);
PAINT AQUA (-6930 6675);
DISPLAY INVISIBLE (-6930 6675);
FORCEPROP 1 LAST PATH I8
J 0
(-6925 6725);
DISPLAY 0.978723 (-6925 6725);
PAINT WHITE (-6925 6725);
DISPLAY INVISIBLE (-6925 6725);
FORCEPROP 2 LAST ROOM MIO_CHASSIS
J 0
(-6925 6725);
DISPLAY 1.404255 (-6925 6725);
PAINT ORANGE (-6925 6725);
DISPLAY INVISIBLE (-6925 6725);
FORCEADD FET_N_DUAL..5
(-7800 7675);
FORCEPROP 1 LAST LOCATION Q9F1
J 0
(-7600 7675);
DISPLAY 0.617021 (-7600 7675);
PAINT AQUA (-7600 7675);
FORCEPROP 1 LAST PART_NUMBER E40049-001
J 0
(-7600 7475);
DISPLAY 0.617021 (-7600 7475);
PAINT BLUE (-7600 7475);
FORCEPROP 1 LAST VALUE NTJD4001N
J 0
(-7600 7625);
DISPLAY 0.617021 (-7600 7625);
PAINT SKYBLUE (-7600 7625);
FORCEPROP 1 LAST MATERIAL FET
J 0
(-7600 7575);
DISPLAY 0.617021 (-7600 7575);
PAINT SKYBLUE (-7600 7575);
FORCEPROP 1 LASTPIN (-7800 7475) $PN 1
J 2
(-7742 7475);
DISPLAY 0.617021 (-7742 7475);
PAINT WHITE (-7742 7475);
FORCEPROP 1 LASTPIN (-8000 7575) $PN 2
J 2
(-7997 7590);
DISPLAY 0.617021 (-7997 7590);
PAINT WHITE (-7997 7590);
FORCEPROP 1 LASTPIN (-7800 7875) $PN 6
J 2
(-7747 7840);
DISPLAY 0.617021 (-7747 7840);
PAINT WHITE (-7747 7840);
FORCEPROP 1 LAST PACK_TYPE SMLF
J 0
(-7600 7525);
DISPLAY 0.978723 (-7600 7525);
PAINT SKYBLUE (-7600 7525);
DISPLAY INVISIBLE (-7600 7525);
FORCEPROP 2 LAST CDS_LIB mstr_discrete
J 0
(-7800 7675);
PAINT MONO (-7800 7675);
DISPLAY INVISIBLE (-7800 7675);
FORCEPROP 2 LAST SEC_TYPE SMLF
J 0
(-7600 7775);
DISPLAY 1.021277 (-7600 7775);
PAINT ORANGE (-7600 7775);
DISPLAY INVISIBLE (-7600 7775);
FORCEPROP 0 LAST BOM_COST SM_CONTROLLER
J 0
(-7600 7875);
DISPLAY 1.021277 (-7600 7875);
PAINT ORANGE (-7600 7875);
DISPLAY INVISIBLE (-7600 7875);
FORCEPROP 2 LAST SEC 1
J 0
(-7600 7775);
DISPLAY 0.680851 (-7600 7775);
PAINT MONO (-7600 7775);
DISPLAY INVISIBLE (-7600 7775);
FORCEPROP 2 LAST CDS_LOCATION Q9F1
J 0
(-7600 7675);
DISPLAY 0.617021 (-7600 7675);
PAINT AQUA (-7600 7675);
DISPLAY INVISIBLE (-7600 7675);
FORCEPROP 1 LAST PATH I80
J 0
(-7600 7725);
DISPLAY 0.978723 (-7600 7725);
PAINT BLUE (-7600 7725);
DISPLAY INVISIBLE (-7600 7725);
FORCEPROP 0 LAST ROOM BMC
J 0
(-7600 7775);
DISPLAY 1.021277 (-7600 7775);
PAINT ORANGE (-7600 7775);
DISPLAY INVISIBLE (-7600 7775);
FORCEADD P3V3_STBY..1
(-7800 8500);
FORCEPROP 3 LASTPIN (-7800 8450) SIG_NAME P3V3_STBY\g
J 0
(-7790 8460);
DISPLAY 0.659574 (-7790 8460);
PAINT MONO (-7790 8460);
DISPLAY INVISIBLE (-7790 8460);
FORCEPROP 1 LAST VOLTAGE 3.3V
J 0
(-7845 8457);
DISPLAY 0.340426 (-7845 8457);
PAINT SKYBLUE (-7845 8457);
DISPLAY INVISIBLE (-7845 8457);
FORCEPROP 1 LAST SIZE 1B
J 0
(-7755 8522);
DISPLAY 0.340426 (-7755 8522);
PAINT GREEN (-7755 8522);
DISPLAY INVISIBLE (-7755 8522);
FORCEPROP 2 LAST CDS_LIB mstr_symbols
J 0
(-7800 8500);
PAINT MONO (-7800 8500);
DISPLAY INVISIBLE (-7800 8500);
FORCEPROP 1 LAST PATH I81
J 0
(-7755 8502);
DISPLAY 0.340426 (-7755 8502);
PAINT GREEN (-7755 8502);
DISPLAY INVISIBLE (-7755 8502);
FORCEPROP 1 LAST BODY_TYPE PLUMBING
J 0
(-7845 8457);
DISPLAY 0.340426 (-7845 8457);
PAINT GREEN (-7845 8457);
DISPLAY INVISIBLE (-7845 8457);
FORCEPROP 1 LAST HDL_POWER P3V3_STBY
J 0
(-8100 8375);
DISPLAY 0.872340 (-8100 8375);
PAINT ORANGE (-8100 8375);
DISPLAY INVISIBLE (-8100 8375);
FORCEADD RES..2
(-7800 8225);
FORCEPROP 1 LAST LOCATION R9F52
J 0
(-7755 8350);
DISPLAY 0.617021 (-7755 8350);
PAINT AQUA (-7755 8350);
FORCEPROP 1 LAST PART_NUMBER G21796-072
J 0
(-7760 8100);
DISPLAY 0.617021 (-7760 8100);
PAINT BLUE (-7760 8100);
FORCEPROP 1 LAST VALUE 4.75K
J 0
(-7755 8300);
DISPLAY 0.617021 (-7755 8300);
PAINT SKYBLUE (-7755 8300);
FORCEPROP 1 LAST TOLERANCE 1%
J 0
(-7755 8250);
DISPLAY 0.617021 (-7755 8250);
PAINT SKYBLUE (-7755 8250);
FORCEPROP 1 LAST PACK_TYPE 0402
J 0
(-7760 8050);
DISPLAY 0.617021 (-7760 8050);
PAINT SKYBLUE (-7760 8050);
FORCEPROP 1 LAST MATERIAL CHIP
J 0
(-7760 8150);
DISPLAY 0.617021 (-7760 8150);
PAINT SKYBLUE (-7760 8150);
FORCEPROP 1 LAST WATTAGE 1/16W
J 0
(-7760 8200);
DISPLAY 0.617021 (-7760 8200);
PAINT SKYBLUE (-7760 8200);
FORCEPROP 1 LASTPIN (-7800 8125) $PN 2
J 0
(-7795 8135);
DISPLAY 0.617021 (-7795 8135);
PAINT ORANGE (-7795 8135);
FORCEPROP 1 LASTPIN (-7800 8325) $PN 1
J 0
(-7795 8287);
DISPLAY 0.617021 (-7795 8287);
PAINT ORANGE (-7795 8287);
FORCEPROP 2 LAST SEC_TYPE 0402
J 0
(-7750 8450);
DISPLAY 1.021277 (-7750 8450);
PAINT ORANGE (-7750 8450);
DISPLAY INVISIBLE (-7750 8450);
FORCEPROP 2 LAST CDS_LIB mstr_discrete
J 0
(-7800 8225);
PAINT MONO (-7800 8225);
DISPLAY INVISIBLE (-7800 8225);
FORCEPROP 0 LAST BOM_COST SM_CONTROLLER
J 0
(-7750 8550);
DISPLAY 1.021277 (-7750 8550);
PAINT ORANGE (-7750 8550);
DISPLAY INVISIBLE (-7750 8550);
FORCEPROP 2 LAST SEC 1
J 0
(-7750 8450);
DISPLAY 0.680851 (-7750 8450);
PAINT MONO (-7750 8450);
DISPLAY INVISIBLE (-7750 8450);
FORCEPROP 2 LAST CDS_LOCATION R9F52
J 0
(-7755 8350);
DISPLAY 0.617021 (-7755 8350);
PAINT AQUA (-7755 8350);
DISPLAY INVISIBLE (-7755 8350);
FORCEPROP 1 LAST PATH I82
J 0
(-7750 8400);
DISPLAY 0.978723 (-7750 8400);
PAINT WHITE (-7750 8400);
DISPLAY INVISIBLE (-7750 8400);
FORCEPROP 0 LAST ROOM BMC
J 0
(-7750 8450);
DISPLAY 1.021277 (-7750 8450);
PAINT ORANGE (-7750 8450);
DISPLAY INVISIBLE (-7750 8450);
FORCEADD GND..1
(-7800 7325);
FORCEPROP 3 LASTPIN (-7800 7375) SIG_NAME GND\g
J 0
(-7790 7385);
DISPLAY 0.659574 (-7790 7385);
PAINT MONO (-7790 7385);
DISPLAY INVISIBLE (-7790 7385);
FORCEPROP 1 LAST VOLTAGE 0.0V
J 0
(-7845 7282);
DISPLAY 0.340426 (-7845 7282);
PAINT SKYBLUE (-7845 7282);
DISPLAY INVISIBLE (-7845 7282);
FORCEPROP 2 LAST CDS_LIB mstr_symbols
J 0
(-7800 7325);
PAINT MONO (-7800 7325);
DISPLAY INVISIBLE (-7800 7325);
FORCEPROP 1 LAST SIZE 1B
J 0
(-7725 7275);
DISPLAY 0.872340 (-7725 7275);
PAINT AQUA (-7725 7275);
DISPLAY INVISIBLE (-7725 7275);
FORCEPROP 1 LAST PATH I83
J 0
(-7725 7325);
DISPLAY 0.872340 (-7725 7325);
PAINT AQUA (-7725 7325);
DISPLAY INVISIBLE (-7725 7325);
FORCEPROP 1 LAST BODY_TYPE PLUMBING
J 0
(-7845 7282);
DISPLAY 0.340426 (-7845 7282);
PAINT GREEN (-7845 7282);
DISPLAY INVISIBLE (-7845 7282);
FORCEPROP 1 LAST HDL_POWER GND
J 0
(-7800 7475);
DISPLAY 0.872340 (-7800 7475);
PAINT GREEN (-7800 7475);
DISPLAY INVISIBLE (-7800 7475);
FORCEADD OFFPAGE..1
(-8750 7575);
FORCEPROP 2 LAST $XR0 119 
J 0
(-9002 7575);
DISPLAY 0.638298 (-9002 7575);
PAINT MONO (-9002 7575);
FORCEPROP 2 LAST $XR1 145 
J 0
(-9122 7575);
DISPLAY 0.638298 (-9122 7575);
PAINT MONO (-9122 7575);
FORCEPROP 2 LAST CDS_LIB mstr_standard
J 0
(-8750 7575);
PAINT MONO (-8750 7575);
DISPLAY INVISIBLE (-8750 7575);
FORCEPROP 2 LAST PATH I84
J 0
(-8700 7650);
DISPLAY 1.021277 (-8700 7650);
PAINT ORANGE (-8700 7650);
DISPLAY INVISIBLE (-8700 7650);
FORCEPROP 1 LAST OFFPAGE TRUE
J 0
(-8425 7450);
DISPLAY 0.872340 (-8425 7450);
PAINT GREEN (-8425 7450);
DISPLAY INVISIBLE (-8425 7450);
FORCEPROP 1 LAST COMMENT_BODY TRUE
J 0
(-8625 7475);
DISPLAY 0.872340 (-8625 7475);
PAINT GREEN (-8625 7475);
DISPLAY INVISIBLE (-8625 7475);
FORCEADD P3V3..1
(-4675 6925);
FORCEPROP 3 LASTPIN (-4675 6875) SIG_NAME P3V3\g
J 0
(-4665 6885);
DISPLAY 0.659574 (-4665 6885);
PAINT MONO (-4665 6885);
DISPLAY INVISIBLE (-4665 6885);
FORCEPROP 1 LAST VOLTAGE 3.3V
J 0
(-4720 6882);
DISPLAY 0.340426 (-4720 6882);
PAINT SKYBLUE (-4720 6882);
DISPLAY INVISIBLE (-4720 6882);
FORCEPROP 2 LAST CDS_LIB mstr_symbols
J 0
(-4675 6925);
PAINT MONO (-4675 6925);
DISPLAY INVISIBLE (-4675 6925);
FORCEPROP 1 LAST SIZE 1B
J 0
(-4630 6947);
DISPLAY 0.340426 (-4630 6947);
PAINT GREEN (-4630 6947);
DISPLAY INVISIBLE (-4630 6947);
FORCEPROP 1 LAST PATH I85
J 0
(-4630 6927);
DISPLAY 0.340426 (-4630 6927);
PAINT GREEN (-4630 6927);
DISPLAY INVISIBLE (-4630 6927);
FORCEPROP 1 LAST BODY_TYPE PLUMBING
J 0
(-4720 6882);
DISPLAY 0.340426 (-4720 6882);
PAINT GREEN (-4720 6882);
DISPLAY INVISIBLE (-4720 6882);
FORCEPROP 1 LAST HDL_POWER P3V3
J 0
(-5000 6800);
DISPLAY 0.872340 (-5000 6800);
PAINT ORANGE (-5000 6800);
DISPLAY INVISIBLE (-5000 6800);
FORCEADD RES..2
R 2
(-7025 6550);
FORCEPROP 1 LAST TOLERANCE 1%
J 2
(-7070 6575);
DISPLAY 0.617021 (-7070 6575);
PAINT SKYBLUE (-7070 6575);
FORCEPROP 1 LAST MATERIAL CHIP
J 2
(-7065 6475);
DISPLAY 0.617021 (-7065 6475);
PAINT SKYBLUE (-7065 6475);
FORCEPROP 1 LASTPIN (-7025 6450) $PN 2
J 2
(-7030 6460);
DISPLAY 0.617021 (-7030 6460);
PAINT MONO (-7030 6460);
FORCEPROP 1 LASTPIN (-7025 6650) $PN 1
J 2
(-7030 6612);
DISPLAY 0.617021 (-7030 6612);
PAINT MONO (-7030 6612);
FORCEPROP 1 LAST PACK_TYPE 0402
J 2
(-7065 6375);
DISPLAY 0.617021 (-7065 6375);
PAINT SKYBLUE (-7065 6375);
FORCEPROP 1 LAST LOCATION R1M11
J 2
(-7070 6675);
DISPLAY 0.617021 (-7070 6675);
PAINT AQUA (-7070 6675);
FORCEPROP 1 LAST VALUE 10.0K
J 2
(-7070 6625);
DISPLAY 0.617021 (-7070 6625);
PAINT SKYBLUE (-7070 6625);
FORCEPROP 1 LAST WATTAGE 1/16W
J 2
(-7065 6525);
DISPLAY 0.617021 (-7065 6525);
PAINT SKYBLUE (-7065 6525);
FORCEPROP 1 LAST PART_NUMBER G21796-016
J 2
(-7040 6425);
DISPLAY 0.617021 (-7040 6425);
PAINT BLUE (-7040 6425);
FORCEPROP 2 LAST SEC_TYPE 0402
J 2
(-7075 6775);
DISPLAY 1.361702 (-7075 6775);
PAINT MONO (-7075 6775);
DISPLAY INVISIBLE (-7075 6775);
FORCEPROP 2 LAST CDS_LIB mstr_discrete
J 2
(-7025 6550);
DISPLAY 1.361702 (-7025 6550);
PAINT ORANGE (-7025 6550);
DISPLAY INVISIBLE (-7025 6550);
FORCEPROP 2 LAST SEC 1
J 2
(-7075 6775);
DISPLAY 0.936170 (-7075 6775);
PAINT MONO (-7075 6775);
DISPLAY INVISIBLE (-7075 6775);
FORCEPROP 2 LAST CDS_LOCATION R1M11
J 2
(-7070 6675);
DISPLAY 0.617021 (-7070 6675);
PAINT AQUA (-7070 6675);
DISPLAY INVISIBLE (-7070 6675);
FORCEPROP 1 LAST PATH I9
J 2
(-7075 6725);
DISPLAY 0.978723 (-7075 6725);
PAINT WHITE (-7075 6725);
DISPLAY INVISIBLE (-7075 6725);
FORCEPROP 2 LAST ROOM MIO_CHASSIS
J 2
(-7075 6725);
DISPLAY 1.404255 (-7075 6725);
PAINT ORANGE (-7075 6725);
DISPLAY INVISIBLE (-7075 6725);
FORCEADD CAD_NOTE..1
(-6425 8725);
FORCEPROP 0 LAST L1 PLEASE PLACE LED NEAR BMC
J 0
(-6575 8600);
DISPLAY 1.021277 (-6575 8600);
PAINT ORANGE (-6575 8600);
FORCEPROP 2 LAST CDS_LIB mstr_symbols
J 0
(-6425 8725);
PAINT MONO (-6425 8725);
DISPLAY INVISIBLE (-6425 8725);
FORCEPROP 1 LAST COMMENT_BODY TRUE
J 0
(-6400 8825);
DISPLAY 0.978723 (-6400 8825);
PAINT ORANGE (-6400 8825);
DISPLAY INVISIBLE (-6400 8825);
FORCEADD INTEL_CORP_BPAGE..1
(-2175 4550);
FORCEPROP 1 LAST CDS_CON_LAST_MODIFIED Tue Dec 01 11:52:14 2015
J 0
(-3600 4875);
PAINT ORANGE (-3600 4875);
DISPLAY INVISIBLE (-3600 4875);
FORCEPROP 1 LAST CUSTOM_TXT_CDS <CURRENT_DESIGN_SHEET> OF <TOTAL_DESIGN_SHEETS>
J 0
(-2675 4575);
PAINT GREEN (-2675 4575);
FORCEPROP 1 LAST CUSTOM_TXT_CDS <CON_LAST_MODIFIED>
J 0
(-4100 4900);
PAINT GREEN (-4100 4900);
FORCEPROP 2 LAST CUSTOM_TXT_CDS <XR_PAGE_TITLE>
J 0
(-10065 9800);
DISPLAY 0.638298 (-10065 9800);
PAINT PINK (-10065 9800);
DISPLAY INVISIBLE (-10065 9800);
FORCEPROP 1 LAST SCH_ADDRESS3 Santa Clara, CA 95052-8119
J 0
(-6150 4575);
DISPLAY 0.617021 (-6150 4575);
PAINT GREEN (-6150 4575);
FORCEPROP 1 LAST SCH_ADDRESS2 P.O. BOX 58119
J 0
(-6150 4625);
DISPLAY 0.617021 (-6150 4625);
PAINT GREEN (-6150 4625);
FORCEPROP 1 LAST SCH_ADDRESS1 2200 Mission College Blvd.
J 0
(-6150 4675);
DISPLAY 0.617021 (-6150 4675);
PAINT GREEN (-6150 4675);
FORCEPROP 1 LAST SCH_TITLE SYSTEM LEDS
J 0
(-10125 4600);
DISPLAY 1.212766 (-10125 4600);
PAINT ORANGE (-10125 4600);
FORCEPROP 1 LAST SCH_NUMBER H4694802
J 0
(-3475 4700);
DISPLAY 1.212766 (-3475 4700);
PAINT YELLOW (-3475 4700);
FORCEPROP 1 LAST SCH_DEPT BESD
J 1
(-6625 4650);
DISPLAY 1.212766 (-6625 4650);
PAINT YELLOW (-6625 4650);
FORCEPROP 1 LAST SCH_REV 2.420
J 0
(-2425 4700);
DISPLAY 0.978723 (-2425 4700);
PAINT YELLOW (-2425 4700);
FORCEPROP 2 LAST CDS_LIB mstr_symbols
J 0
(-2175 4550);
PAINT ORANGE (-2175 4550);
DISPLAY INVISIBLE (-2175 4550);
FORCEPROP 2 LAST PAGE_BORDER TRUE
J 0
(-10065 9800);
DISPLAY 1.021277 (-10065 9800);
PAINT PINK (-10065 9800);
DISPLAY INVISIBLE (-10065 9800);
FORCEPROP 2 LAST ROOM WBG_SPI
J 0
(-10050 9850);
PAINT MONO (-10050 9850);
DISPLAY INVISIBLE (-10050 9850);
FORCEPROP 1 LAST COMMENT_BODY TRUE
J 0
(-2163 4562);
DISPLAY 0.510638 (-2163 4562);
PAINT GREEN (-2163 4562);
DISPLAY INVISIBLE (-2163 4562);
FORCEPROP 2 LAST CDS_XR_PAGE_TITLE CR-177 : @BASEBOARD_FAB2_LIB.BASEBOARD_FAB2(SCH_1):PAGE177
J 0
(-10065 9800);
DISPLAY 0.638298 (-10065 9800);
PAINT PINK (-10065 9800);
DISPLAY INVISIBLE (-10065 9800);
WIRE 16 -1 (-7025 6650)(-7025 6700);
WIRE 16 -1 (-7025 6700)(-6975 6700);
WIRE 16 -1 (-6975 6725)(-6975 6700);
WIRE 16 -1 (-6975 6700)(-6975 6650);
WIRE 16 -1 (-3825 8375)(-3825 8300);
WIRE 16 -1 (-3825 8950)(-3825 9000);
WIRE 16 -1 (-5625 5675)(-5625 5525);
WIRE 16 -1 (-5625 5325)(-5625 5125);
WIRE 16 -1 (-7200 7850)(-7200 7700);
WIRE 16 -1 (-8475 7950)(-8475 8075);
WIRE 16 -1 (-7200 9075)(-7200 8925);
WIRE 16 -1 (-7800 8325)(-7800 8450);
WIRE 16 -1 (-7800 7375)(-7800 7475);
WIRE 16 -1 (-4675 6875)(-4675 6700);
WIRE 16 -1 (-7650 6325)(-7025 6325);
FORCEPROP 2 LAST SIG_NAME LED_SATA_ACT_R_N
J 0
(-7610 6335);
DISPLAY 0.617021 (-7610 6335);
PAINT ORANGE (-7610 6335);
FORCEPROP 2 LASTPROP $XRERR UNIQUE?
J 0
(-7850 6335);
DISPLAY 0.638298 (-7850 6335);
PAINT MONO (-7850 6335);
DISPLAY INVISIBLE (-7850 6335);
WIRE 16 -1 (-7025 6325)(-6700 6325);
WIRE 16 -1 (-7025 6450)(-7025 6325);
WIRE 16 -1 (-8600 6225)(-7650 6225);
FORCEPROP 2 LAST SIG_NAME LED_PCH_SSATA_HDD_N
J 0
(-8585 6235);
DISPLAY 0.617021 (-8585 6235);
PAINT ORANGE (-8585 6235);
WIRE 16 -1 (-7450 6225)(-6975 6225);
WIRE 16 -1 (-6975 6225)(-6700 6225);
WIRE 16 -1 (-6975 6450)(-6975 6225);
FORCEPROP 2 LAST SIG_NAME LED_SAS_ACT_R_N
J 0
(-7235 6235);
DISPLAY 0.617021 (-7235 6235);
PAINT ORANGE (-7235 6235);
FORCEPROP 2 LASTPROP $XRERR UNIQUE?
J 0
(-7475 6235);
DISPLAY 0.638298 (-7475 6235);
PAINT MONO (-7475 6235);
DISPLAY INVISIBLE (-7475 6235);
WIRE 16 -1 (-8475 7750)(-8475 7575);
WIRE 16 -1 (-8475 7575)(-8000 7575);
WIRE 16 -1 (-8700 7575)(-8475 7575);
FORCEPROP 2 LAST SIG_NAME FM_BMC_FAULT_LED_N
J 0
(-8635 7585);
DISPLAY 0.617021 (-8635 7585);
PAINT ORANGE (-8635 7585);
WIRE 16 -1 (-8600 6325)(-7850 6325);
FORCEPROP 2 LAST SIG_NAME LED_PCH_SATA_HDD_N
J 0
(-8585 6335);
DISPLAY 0.617021 (-8585 6335);
PAINT ORANGE (-8585 6335);
WIRE 16 -1 (-7800 7950)(-7400 7950);
FORCEPROP 2 LAST SIG_NAME FM_BMC_FAULT_LED
J 0
(-7760 7960);
DISPLAY 0.617021 (-7760 7960);
PAINT ORANGE (-7760 7960);
FORCEPROP 2 LASTPROP $XRERR UNIQUE?
J 0
(-8000 7960);
DISPLAY 0.638298 (-8000 7960);
PAINT MONO (-8000 7960);
DISPLAY INVISIBLE (-8000 7960);
WIRE 16 -1 (-7800 7950)(-7800 8125);
WIRE 16 -1 (-7800 7875)(-7800 7950);
WIRE 16 -1 (-6400 6275)(-5650 6275);
FORCEPROP 2 LAST SIG_NAME FP_LED_HDD_ACTIVITY_AND_N
J 0
(-6310 6285);
DISPLAY 0.617021 (-6310 6285);
PAINT ORANGE (-6310 6285);
FORCEPROP 2 LASTPROP $XRERR UNIQUE?
J 0
(-6550 6285);
DISPLAY 0.638298 (-6550 6285);
PAINT MONO (-6550 6285);
DISPLAY INVISIBLE (-6550 6285);
WIRE 16 -1 (-4675 6500)(-4675 6275);
WIRE 16 -1 (-4675 6275)(-5450 6275);
FORCEPROP 2 LAST SIG_NAME FP_LED_HDD_ACTIVITY_AND_R_N
J 0
(-5360 6285);
DISPLAY 0.617021 (-5360 6285);
PAINT ORANGE (-5360 6285);
FORCEPROP 2 LASTPROP $XRERR UNIQUE?
J 0
(-5600 6285);
DISPLAY 0.638298 (-5600 6285);
PAINT MONO (-5600 6285);
DISPLAY INVISIBLE (-5600 6285);
WIRE 16 273 (-4975 7925)(-4975 9400);
WIRE 16 273 (-4975 7925)(-2275 7925);
WIRE 16 -1 (-7200 8250)(-7200 8375);
FORCEPROP 2 LAST SIG_NAME FM_RED_LED_CATHODE
J 0
(-7160 8310);
DISPLAY 0.617021 (-7160 8310);
PAINT ORANGE (-7160 8310);
FORCEPROP 2 LASTPROP $XRERR UNIQUE?
J 0
(-7400 8310);
DISPLAY 0.638298 (-7400 8310);
PAINT MONO (-7400 8310);
DISPLAY INVISIBLE (-7400 8310);
WIRE 16 -1 (-7200 8575)(-7200 8725);
FORCEPROP 2 LAST SIG_NAME FM_RED_LED_ANODE
J 0
(-7160 8610);
DISPLAY 0.617021 (-7160 8610);
PAINT ORANGE (-7160 8610);
FORCEPROP 2 LASTPROP $XRERR UNIQUE?
J 0
(-7400 8610);
DISPLAY 0.638298 (-7400 8610);
PAINT MONO (-7400 8610);
DISPLAY INVISIBLE (-7400 8610);
WIRE 16 -1 (-3825 8750)(-3825 8575);
FORCEPROP 2 LAST SIG_NAME LED_P5V_STBY
J 0
(-3800 8610);
DISPLAY 0.617021 (-3800 8610);
PAINT ORANGE (-3800 8610);
FORCEPROP 2 LASTPROP $XRERR UNIQUE?
J 0
(-4040 8610);
DISPLAY 0.638298 (-4040 8610);
PAINT MONO (-4040 8610);
DISPLAY INVISIBLE (-4040 8610);
DOT 1 (-6975 6225);
DOT 1 (-6975 6700);
DOT 1 (-7025 6325);
DOT 1 (-8475 7575);
DOT 1 (-7800 7950);
FORCENOTE
ROOM=MIO_CHASSIS
(-10105 4748) 0;
DISPLAY LEFT (-10105 4748);
DISPLAY 0.617021 (-10105 4748);
PAINT PURPLE (-10105 4748);
FORCENOTE
CAD NOTE:
(-7175 5800) 0;
DISPLAY LEFT (-7175 5800);
DISPLAY 1.021277 (-7175 5800);
PAINT PURPLE (-7175 5800);
FORCENOTE
POWER PINS
(-7150 5700) 0;
DISPLAY LEFT (-7150 5700);
DISPLAY 1.021277 (-7150 5700);
PAINT PURPLE (-7150 5700);
FORCENOTE
ADD 0.1UF CAPS FOR VCC
(-7175 5750) 0;
DISPLAY LEFT (-7175 5750);
DISPLAY 1.021277 (-7175 5750);
PAINT PURPLE (-7175 5750);
QUIT
